# S9S_MB_2U (Grand Teton) — schematic parts with pin connectivity, parts 1616–1616 of 6093; source: Cadence DE-HDL packaged netlist (pstxprt.dat, pstxnet.dat, pstchip.dat)

J23  SCONN288_ADR50017P130CC  SCONN288_ADR50017-P130CC IO  pkg DDR288S_1-1VXB  page 104
  1  VIN_BULK0  POWER  = P12V_S3_AUX_CPU1_NVDIMM
  2  RFU0  TRI  = TP_CHD_CPU1_DIMM1_FRU_0
  3  VIN_MGMT  POWER  = P3V3_AUX
  4  HSCL  IN  = I3C_SPD_DDRABCD_CPU1_LVC1_SCL_6
  5  HSDA  BI  = I3C_SPD_DDRABCD_CPU1_LVC1_SDA
  6  VSS0  POWER  = GND
  7  DQ0_A  BI  = M_D_CPU1_SA_DQ<0>
  8  VSS1  POWER  = GND
  9  DQ1_A  BI  = M_D_CPU1_SA_DQ<1>
  10  VSS2  POWER  = GND
  11  DQS0_A_T  BI  = M_D_CPU1_SA_DQS_DP<0>
  12  DQS0_A_C  BI  = M_D_CPU1_SA_DQS_DN<0>
  13  VSS3  POWER  = GND
  14  DQ4_A  BI  = M_D_CPU1_SA_DQ<4>
  15  VSS4  POWER  = GND
  16  DQ5_A  BI  = M_D_CPU1_SA_DQ<5>
  17  VSS5  POWER  = GND
  18  DQ8_A  BI  = M_D_CPU1_SA_DQ<8>
  19  VSS6  POWER  = GND
  20  DQ9_A  BI  = M_D_CPU1_SA_DQ<9>
  21  VSS7  POWER  = GND
  22  DQS1_A_T  BI  = M_D_CPU1_SA_DQS_DP<1>
  23  DQS1_A_C  BI  = M_D_CPU1_SA_DQS_DN<1>
  24  VSS8  POWER  = GND
  25  DQ12_A  BI  = M_D_CPU1_SA_DQ<12>
  26  VSS9  POWER  = GND
  27  DQ13_A  BI  = M_D_CPU1_SA_DQ<13>
  28  VSS10  POWER  = GND
  29  DQ16_A  BI  = M_D_CPU1_SA_DQ<16>
  30  VSS11  POWER  = GND
  31  DQ17_A  BI  = M_D_CPU1_SA_DQ<17>
  32  VSS12  POWER  = GND
  33  DQS2_A_T  BI  = M_D_CPU1_SA_DQS_DP<2>
  34  DQS2_A_C  BI  = M_D_CPU1_SA_DQS_DN<2>
  35  VSS13  POWER  = GND
  36  DQ20_A  BI  = M_D_CPU1_SA_DQ<20>
  37  VSS14  POWER  = GND
  38  DQ21_A  BI  = M_D_CPU1_SA_DQ<21>
  39  VSS15  POWER  = GND
  40  DQ24_A  BI  = M_D_CPU1_SA_DQ<24>
  41  VSS16  POWER  = GND
  42  DQ25_A  BI  = M_D_CPU1_SA_DQ<25>
  43  VSS17  POWER  = GND
  44  DQS3_A_T  BI  = M_D_CPU1_SA_DQS_DP<3>
  45  DQS3_A_C  BI  = M_D_CPU1_SA_DQS_DN<3>
  46  VSS18  POWER  = GND
  47  DQ28_A  BI  = M_D_CPU1_SA_DQ<28>
  48  VSS19  POWER  = GND
  49  DQ29_A  BI  = M_D_CPU1_SA_DQ<29>
  50  VSS20  POWER  = GND
  51  CB0_A  BI  = M_D_CPU1_SA_CB<0>
  52  VSS21  POWER  = GND
  53  CB1_A  BI  = M_D_CPU1_SA_CB<1>
  54  VSS22  POWER  = GND
  55  DQS4_A_T  BI  = M_D_CPU1_SA_DQS_DP<4>
  56  DQS4_A_C  BI  = M_D_CPU1_SA_DQS_DN<4>
  57  VSS23  POWER  = GND
  58  CB4_A  BI  = M_D_CPU1_SA_CB<4>
  59  VSS24  POWER  = GND
  60  CB5_A  BI  = M_D_CPU1_SA_CB<5>
  61  VSS25  POWER  = GND
  62  ALERT_N  OUT  = M_D_CPU1_ALERT_N
  63  VSS26  POWER  = GND
  64  CS0_A_N  IN  = M_D_CPU1_SA_CS_N<0>
  65  VSS27  POWER  = GND
  66  CA0_A  IN  = M_D_CPU1_SA_CA<0>
  67  VSS28  POWER  = GND
  68  CA2_A  IN  = M_D_CPU1_SA_CA<2>
  69  VSS29  POWER  = GND
  70  CA4_A  IN  = M_D_CPU1_SA_CA<4>
  71  VSS30  POWER  = GND
  72  CA6_A  IN  = M_D_CPU1_SA_CA<6>
  73  VSS31  POWER  = GND
  74  PAR_A  IN  = M_D_CPU1_SA_PAR
  75  VSS32  POWER  = GND
  76  CA0_B  IN  = M_D_CPU1_SB_CA<0>
  77  VSS33  POWER  = GND
  78  CA2_B  IN  = M_D_CPU1_SB_CA<2>
  79  VSS34  POWER  = GND
  80  CA4_B  IN  = M_D_CPU1_SB_CA<4>
  81  VSS35  POWER  = GND
  82  CA6_B  IN  = M_D_CPU1_SB_CA<6>
  83  VSS36  POWER  = GND
  84  CS0_B_N  IN  = M_D_CPU1_SB_CS_N<0>
  85  VSS37  POWER  = GND
  86  \lbd||rsp_a_n\  OUT  = M_D_CPU1_SA_RSP<0>
  87  \lbs||rsp_b_n\  OUT  = M_D_CPU1_SB_RSP<0>
  88  VSS38  POWER  = GND
  89  CB4_B  BI  = M_D_CPU1_SB_CB<4>
  90  VSS39  POWER  = GND
  91  CB5_B  BI  = M_D_CPU1_SB_CB<5>
  92  VSS40  POWER  = GND
  93  \dqs9_b_t||tdqs9_b_t||dbi4_b_n\  BI  = M_D_CPU1_SB_DQS_DP<9>
  94  \dqs9_b_c||tdqs9_b_c\  BI  = M_D_CPU1_SB_DQS_DN<9>
  95  VSS41  POWER  = GND
  96  CB0_B  BI  = M_D_CPU1_SB_CB<0>
  97  VSS42  POWER  = GND
  98  CB1_B  BI  = M_D_CPU1_SB_CB<1>
  99  VSS43  POWER  = GND
  100  DQ0_B  BI  = M_D_CPU1_SB_DQ<0>
  101  VSS44  POWER  = GND
  102  DQ1_B  BI  = M_D_CPU1_SB_DQ<1>
  103  VSS45  POWER  = GND
  104  DQS0_B_T  BI  = M_D_CPU1_SB_DQS_DP<0>
  105  DQS0_B_C  BI  = M_D_CPU1_SB_DQS_DN<0>
  106  VSS46  POWER  = GND
  107  DQ4_B  BI  = M_D_CPU1_SB_DQ<4>
  108  VSS47  POWER  = GND
  109  DQ5_B  BI  = M_D_CPU1_SB_DQ<5>
  110  VSS48  POWER  = GND
  111  DQ8_B  BI  = M_D_CPU1_SB_DQ<8>
  112  VSS49  POWER  = GND
  113  DQ9_B  BI  = M_D_CPU1_SB_DQ<9>
  114  VSS50  POWER  = GND
  115  DQS1_B_T  BI  = M_D_CPU1_SB_DQS_DP<1>
  116  DQS1_B_C  BI  = M_D_CPU1_SB_DQS_DN<1>
  117  VSS51  POWER  = GND
  118  DQ12_B  BI  = M_D_CPU1_SB_DQ<12>
  119  VSS52  POWER  = GND
  120  DQ13_B  BI  = M_D_CPU1_SB_DQ<13>
  121  VSS53  POWER  = GND
  122  DQ16_B  BI  = M_D_CPU1_SB_DQ<16>
  123  VSS54  POWER  = GND
  124  DQ17_B  BI  = M_D_CPU1_SB_DQ<17>
  125  VSS55  POWER  = GND
  126  DQS2_B_T  BI  = M_D_CPU1_SB_DQS_DP<2>
  127  DQS2_B_C  BI  = M_D_CPU1_SB_DQS_DN<2>
  128  VSS56  POWER  = GND
  129  DQ20_B  BI  = M_D_CPU1_SB_DQ<20>
  130  VSS57  POWER  = GND
  131  DQ21_B  BI  = M_D_CPU1_SB_DQ<21>
  132  VSS58  POWER  = GND
  133  DQ24_B  BI  = M_D_CPU1_SB_DQ<24>
  134  VSS59  POWER  = GND
  135  DQ25_B  BI  = M_D_CPU1_SB_DQ<25>
  136  VSS60  POWER  = GND
  137  DQS3_B_T  BI  = M_D_CPU1_SB_DQS_DP<3>
  138  DQS3_B_C  BI  = M_D_CPU1_SB_DQS_DN<3>
  139  VSS61  POWER  = GND
  140  DQ28_B  BI  = M_D_CPU1_SB_DQ<28>
  141  VSS62  POWER  = GND
  142  DQ29_B  BI  = M_D_CPU1_SB_DQ<29>
  143  VSS63  POWER  = GND
  144  RFU1  TRI  = TP_CHD_CPU1_DIMM1_FRU_1
  145  VIN_BULK1  POWER  = P12V_S3_AUX_CPU1_NVDIMM
  146  VIN_BULK2  POWER  = P12V_S3_AUX_CPU1_NVDIMM
  147  \pwr_good||fail_n\  BI  = PWRGD_CHD_CPU1_DIMM1
  148  HSA  IN  = PD_CHD_CPU1_DIMM1_SAA
  149  RFU2  TRI  = TP_CHD_CPU1_DIMM1_FRU_2
  150  RFU3  TRI  = TP_CHD_CPU1_DIMM1_FRU_3
  151  VSS64  POWER  = GND
  152  DQ2_A  BI  = M_D_CPU1_SA_DQ<2>
  153  VSS65  POWER  = GND
  154  DQ3_A  BI  = M_D_CPU1_SA_DQ<3>
  155  VSS66  POWER  = GND
  156  \dqs5_a_c||tdqs5_a_c||dqs5_a_t||tdqs5_a_t\  BI  = M_D_CPU1_SA_DQS_DN<5>
  157  \dqs5_a_t||tdqs5_a_t\  BI  = M_D_CPU1_SA_DQS_DP<5>
  158  VSS67  POWER  = GND
  159  DQ6_A  BI  = M_D_CPU1_SA_DQ<6>
  160  VSS68  POWER  = GND
  161  DQ7_A  BI  = M_D_CPU1_SA_DQ<7>
  162  VSS69  POWER  = GND
  163  DQ10_A  BI  = M_D_CPU1_SA_DQ<10>
  164  VSS70  POWER  = GND
  165  DQ11_A  BI  = M_D_CPU1_SA_DQ<11>
  166  VSS71  POWER  = GND
  167  \dqs6_a_c||tdqs6_a_c||dqs6_a_t||tdqs6_a_t\  BI  = M_D_CPU1_SA_DQS_DN<6>
  168  \dqs6_a_t||tdqs6_a_t\  BI  = M_D_CPU1_SA_DQS_DP<6>
  169  VSS72  POWER  = GND
  170  DQ14_A  BI  = M_D_CPU1_SA_DQ<14>
  171  VSS73  POWER  = GND
  172  DQ15_A  BI  = M_D_CPU1_SA_DQ<15>
  173  VSS74  POWER  = GND
  174  DQ18_A  BI  = M_D_CPU1_SA_DQ<18>
  175  VSS75  POWER  = GND
  176  DQ19_A  BI  = M_D_CPU1_SA_DQ<19>
  177  VSS76  POWER  = GND
  178  \dqs7_a_c||tdqs7_a_c\  BI  = M_D_CPU1_SA_DQS_DN<7>
  179  \dqs7_a_t||tdqs7_a_t\  BI  = M_D_CPU1_SA_DQS_DP<7>
  180  VSS77  POWER  = GND
  181  DQ22_A  BI  = M_D_CPU1_SA_DQ<22>
  182  VSS78  POWER  = GND
  183  DQ23_A  BI  = M_D_CPU1_SA_DQ<23>
  184  VSS79  POWER  = GND
  185  DQ26_A  BI  = M_D_CPU1_SA_DQ<26>
  186  VSS80  POWER  = GND
  187  DQ27_A  BI  = M_D_CPU1_SA_DQ<27>
  188  VSS81  POWER  = GND
  189  \dqs8_a_c||tdqs8_a_c\  BI  = M_D_CPU1_SA_DQS_DN<8>
  190  \dqs8_a_t||tdqs8_a_t\  BI  = M_D_CPU1_SA_DQS_DP<8>
  191  VSS82  POWER  = GND
  192  DQ30_A  BI  = M_D_CPU1_SA_DQ<30>
  193  VSS83  POWER  = GND
  194  DQ31_A  BI  = M_D_CPU1_SA_DQ<31>
  195  VSS84  POWER  = GND
  196  CB2_A  BI  = M_D_CPU1_SA_CB<2>
  197  VSS85  POWER  = GND
  198  CB3_A  BI  = M_D_CPU1_SA_CB<3>
  199  VSS86  POWER  = GND
  200  \dqs9_a_c||tdqs9_a_c\  BI  = M_D_CPU1_SA_DQS_DN<9>
  201  \dqs9_a_t||tdqs9_a_t\  BI  = M_D_CPU1_SA_DQS_DP<9>
  202  VSS87  POWER  = GND
  203  CB6_A  BI  = M_D_CPU1_SA_CB<6>
  204  VSS88  POWER  = GND
  205  CB7_A  BI  = M_D_CPU1_SA_CB<7>
  206  VSS89  POWER  = GND
  207  RESET_N  IN  = RST_M_CD_CPU1_FPGA_N
  208  VSS90  POWER  = GND
  209  CS1_A_N  IN  = M_D_CPU1_SA_CS_N<1>
  210  VSS91  POWER  = GND
  211  CA1_A  IN  = M_D_CPU1_SA_CA<1>
  212  VSS92  POWER  = GND
  213  CA3_A  IN  = M_D_CPU1_SA_CA<3>
  214  VSS93  POWER  = GND
  215  CA5_A  IN  = M_D_CPU1_SA_CA<5>
  216  VSS94  POWER  = GND
  217  CK_T  IN  = M_D_CPU1_CLK_DP<0>
  218  CK_C  IN  = M_D_CPU1_CLK_DN<0>
  219  VSS95  POWER  = GND
  220  RFU4  TRI  = TP_CHD_CPU1_DIMM1_FRU_4
  221  CA1_B  IN  = M_D_CPU1_SB_CA<1>
  222  VSS96  POWER  = GND
  223  CA3_B  IN  = M_D_CPU1_SB_CA<3>
  224  VSS97  POWER  = GND
  225  CA5_B  IN  = M_D_CPU1_SB_CA<5>
  226  VSS98  POWER  = GND
  227  PAR_B  IN  = M_D_CPU1_SB_PAR
  228  VSS99  POWER  = GND
  229  CS1_B_N  IN  = M_D_CPU1_SB_CS_N<1>
  230  VSS100  POWER  = GND
  231  RFU5  TRI  = TP_CHD_CPU1_DIMM1_FRU_5
  232  RFU6  TRI  = TP_CHD_CPU1_DIMM1_FRU_6
  233  VSS101  POWER  = GND
  234  CB6_B  BI  = M_D_CPU1_SB_CB<6>
  235  VSS102  POWER  = GND
  236  CB7_B  BI  = M_D_CPU1_SB_CB<7>
  237  VSS103  POWER  = GND
  238  DQS4_B_C  BI  = M_D_CPU1_SB_DQS_DN<4>
  239  DQS4_B_T  BI  = M_D_CPU1_SB_DQS_DP<4>
  240  VSS104  POWER  = GND
  241  CB2_B  BI  = M_D_CPU1_SB_CB<2>
  242  VSS105  POWER  = GND
  243  CB3_B  BI  = M_D_CPU1_SB_CB<3>
  244  VSS106  POWER  = GND
  245  DQ2_B  BI  = M_D_CPU1_SB_DQ<2>
  246  VSS107  POWER  = GND
  247  DQ3_B  BI  = M_D_CPU1_SB_DQ<3>
  248  VSS108  POWER  = GND
  249  \dqs5_b_c||tdqs5_b_c\  BI  = M_D_CPU1_SB_DQS_DN<5>
  250  \dqs5_b_t||tdqs5_b_t\  BI  = M_D_CPU1_SB_DQS_DP<5>
  251  VSS109  POWER  = GND
  252  DQ6_B  BI  = M_D_CPU1_SB_DQ<6>
  253  VSS110  POWER  = GND
  254  DQ7_B  BI  = M_D_CPU1_SB_DQ<7>
  255  VSS111  POWER  = GND
  256  DQ10_B  BI  = M_D_CPU1_SB_DQ<10>
  257  VSS112  POWER  = GND
  258  DQ11_B  BI  = M_D_CPU1_SB_DQ<11>
  259  VSS113  POWER  = GND
  260  \dqs6_b_c||tdqs6_b_c\  BI  = M_D_CPU1_SB_DQS_DN<6>
  261  \dqs6_b_t||tdqs6_b_t\  BI  = M_D_CPU1_SB_DQS_DP<6>
  262  VSS114  POWER  = GND
  263  DQ14_B  BI  = M_D_CPU1_SB_DQ<14>
  264  VSS115  POWER  = GND
  265  DQ15_B  BI  = M_D_CPU1_SB_DQ<15>
  266  VSS116  POWER  = GND
  267  DQ18_B  BI  = M_D_CPU1_SB_DQ<18>
  268  VSS117  POWER  = GND
  269  DQ19_B  BI  = M_D_CPU1_SB_DQ<19>
  270  VSS118  POWER  = GND
  271  \dqs7_b_c||tdqs7_b_c\  BI  = M_D_CPU1_SB_DQS_DN<7>
  272  \dqs7_b_t||tdqs7_b_t\  BI  = M_D_CPU1_SB_DQS_DP<7>
  273  VSS119  POWER  = GND
  274  DQ22_B  BI  = M_D_CPU1_SB_DQ<22>
  275  VSS120  POWER  = GND
  276  DQ23_B  BI  = M_D_CPU1_SB_DQ<23>
  277  VSS121  POWER  = GND
  278  DQ26_B  BI  = M_D_CPU1_SB_DQ<26>
  279  VSS122  POWER  = GND
  280  DQ27_B  BI  = M_D_CPU1_SB_DQ<27>
  281  VSS123  POWER  = GND
  282  \dqs8_b_c||tdqs8_b_c\  BI  = M_D_CPU1_SB_DQS_DN<8>
  283  \dqs8_b_t||tdqs8_b_t\  BI  = M_D_CPU1_SB_DQS_DP<8>
  284  VSS124  POWER  = GND
  285  DQ30_B  BI  = M_D_CPU1_SB_DQ<30>
  286  VSS125  POWER  = GND
  287  DQ31_B  BI  = M_D_CPU1_SB_DQ<31>
  288  VSS126  POWER  = GND
  G1  G1  POWER  = GND
  G2  G2  POWER  = GND
  G3  G3  POWER  = GND
